# S9S_MB_2U (Grand Teton) — schematic netlist excerpt (pin names and nets, part order shuffled) for the footprints in the layout excerpt that follows; sources: Cadence DE-HDL packaged netlist, KiCad conversion of 03242023_DA0F0TMBIJ0_F0T_Motherboard_J_brd_V01_OCP.brd

Q136  MOSFET_NCH_DUAL  PJT138K IC  pkg SOT363XD  page 145
  S1  = GND
  G1  = GPU_3V3IO_RSVD4
  D2  = GPU_3V3IO_RSVD4_ISO
  S2  = GND
  G2  = GPU_3V3IO_RSVD4_N
  D1  = GPU_3V3IO_RSVD4_N

R4735  Q_RES  0 5% CHIP  pkg 0402LF  page 227 : A = PRSNT_CABLE_SWB_B2_ISO_N ; B = PRSNT_CABLE_SWB_B2_ISO_R_N

(kicad_pcb
	(version 20260206)
	(generator "pcbnew")
	(generator_version "10.0")
	(general
		(thickness 1.6)
		(legacy_teardrops no)
	)
	(paper "A4")
	(title_block
		(title "03242023_DA0F0TMBIJ0_F0T_Motherboard_J_brd_V01_OCP.brd")
		(comment 1 "Grand Teton / footprints 3756-3757 of 6105")
	)
	(layers
		(0 "F.Cu" signal "TOP")
		(4 "In1.Cu" signal "GND")
		(6 "In2.Cu" signal "IN1")
		(8 "In3.Cu" signal "GND1")
		(10 "In4.Cu" signal "IN2")
		(12 "In5.Cu" signal "GND2")
		(14 "In6.Cu" signal "IN3")
		(16 "In7.Cu" signal "GND3")
		(18 "In8.Cu" signal "VCC")
		(20 "In9.Cu" signal "VCC1")
		(22 "In10.Cu" signal "GND4")
		(24 "In11.Cu" signal "IN4")
		(26 "In12.Cu" signal "GND5")
		(28 "In13.Cu" signal "IN5")
		(30 "In14.Cu" signal "GND6")
		(32 "In15.Cu" signal "IN6")
		(34 "In16.Cu" signal "GND7")
		(2 "B.Cu" signal "BOTTOM")
		(9 "F.Adhes" user "F.Adhesive")
		(11 "B.Adhes" user "B.Adhesive")
		(13 "F.Paste" user "Package Geometry/Pastemask Top")
		(15 "B.Paste" user "Package Geometry/Pastemask Bottom")
		(5 "F.SilkS" user "Ref Des/Silkscreen Top")
		(7 "B.SilkS" user "Ref Des/Silkscreen Bottom")
		(1 "F.Mask" user "Board Geometry/Soldermask Top")
		(3 "B.Mask" user "Board Geometry/Soldermask Bottom")
		(17 "Dwgs.User" user "User.Drawings")
		(19 "Cmts.User" user "User.Comments")
		(21 "Eco1.User" user "User.Eco1")
		(23 "Eco2.User" user "User.Eco2")
		(25 "Edge.Cuts" user "Board Geometry/Outline")
		(27 "Margin" user)
		(31 "F.CrtYd" user "Package Geometry/Place Bound Top")
		(29 "B.CrtYd" user "Package Geometry/Place Bound Bottom")
		(35 "F.Fab" user "Ref Des/Assembly Top")
		(33 "B.Fab" user "Ref Des/Assembly Bottom")
	)
	(footprint ""
		(layer "F.Cu")
		(at 364.978442 -393.33805)
		(property "Reference" "Q136"
			(at -1.4224 -1.768348 0)
			(unlocked yes)
			(layer "F.SilkS")
			(effects
				(font
					(size 0.7874 0.5842)
					(thickness 0.1524)
				)
				(justify left)
			)
		)
		(property "Value" ""
			(at 0 0 0)
			(layer "F.Fab")
			(effects
				(font
					(size 1.27 1.27)
				)
			)
		)
		(duplicate_pad_numbers_are_jumpers no)
		(fp_line
			(start -1.332738 -1.100074)
			(end -0.4826 -1.100074)
			(stroke
				(width 0.1524)
				(type default)
			)
			(layer "F.SilkS")
		)
		(fp_line
			(start -1.332738 1.100074)
			(end -1.332738 -1.100074)
			(stroke
				(width 0.1524)
				(type default)
			)
			(layer "F.SilkS")
		)
		(fp_line
			(start -0.4826 -1.100074)
			(end 0 -0.541274)
			(stroke
				(width 0.1524)
				(type default)
			)
			(layer "F.SilkS")
		)
		(fp_line
			(start 0 -0.541274)
			(end 0.4826 -1.100074)
			(stroke
				(width 0.1524)
				(type default)
			)
			(layer "F.SilkS")
		)
		(fp_line
			(start 0.4826 -1.100074)
			(end 1.332738 -1.100074)
			(stroke
				(width 0.1524)
				(type default)
			)
			(layer "F.SilkS")
		)
		(fp_line
			(start 1.332738 -1.100074)
			(end 1.332738 1.100074)
			(stroke
				(width 0.1524)
				(type default)
			)
			(layer "F.SilkS")
		)
		(fp_line
			(start 1.332738 1.100074)
			(end -1.332738 1.100074)
			(stroke
				(width 0.1524)
				(type default)
			)
			(layer "F.SilkS")
		)
		(fp_poly
			(pts
				(xy -2.2352 -1.001014) (xy -1.533144 -0.649986) (xy -2.2352 -0.298958)
			)
			(stroke
				(width 0)
				(type default)
			)
			(fill yes)
			(layer "F.SilkS")
		)
		(fp_line
			(start -0.674878 -1.100074)
			(end 0.674878 -1.100074)
			(stroke
				(width 0.1)
				(type default)
			)
			(layer "F.Fab")
		)
		(fp_line
			(start -0.674878 1.100074)
			(end -0.674878 -1.100074)
			(stroke
				(width 0.1)
				(type default)
			)
			(layer "F.Fab")
		)
		(fp_line
			(start 0.674878 -1.100074)
			(end 0.674878 1.100074)
			(stroke
				(width 0.1)
				(type default)
			)
			(layer "F.Fab")
		)
		(fp_line
			(start 0.674878 1.100074)
			(end -0.674878 1.100074)
			(stroke
				(width 0.1)
				(type default)
			)
			(layer "F.Fab")
		)
		(fp_poly
			(pts
				(xy -2.2352 -0.298958) (xy -2.2352 -1.001014) (xy -1.533144 -0.649986)
			)
			(stroke
				(width 0)
				(type default)
			)
			(fill yes)
			(layer "F.Fab")
		)
		(pad "1" smd rect
			(at -0.94996 -0.649986 90)
			(size 0.4318 0.508)
			(layers "F.Cu" "F.Mask" "F.Paste")
			(net "GND")
		)
		(pad "2" smd rect
			(at -0.94996 0 90)
			(size 0.4318 0.508)
			(layers "F.Cu" "F.Mask" "F.Paste")
			(net "GPU_3V3IO_RSVD4")
		)
		(pad "3" smd rect
			(at -0.94996 0.649986 90)
			(size 0.4318 0.508)
			(layers "F.Cu" "F.Mask" "F.Paste")
			(net "GPU_3V3IO_RSVD4_ISO")
		)
		(pad "4" smd rect
			(at 0.94996 0.649986 90)
			(size 0.4318 0.508)
			(layers "F.Cu" "F.Mask" "F.Paste")
			(net "GND")
		)
		(pad "5" smd rect
			(at 0.94996 0 90)
			(size 0.4318 0.508)
			(layers "F.Cu" "F.Mask" "F.Paste")
			(net "GPU_3V3IO_RSVD4_N")
		)
		(pad "6" smd rect
			(at 0.94996 -0.649986 90)
			(size 0.4318 0.508)
			(layers "F.Cu" "F.Mask" "F.Paste")
			(net "GPU_3V3IO_RSVD4_N")
		)
	)
	(footprint ""
		(layer "F.Cu")
		(at 21.7932 -410.7942 90)
		(property "Reference" "R4735"
			(at 0 0 90)
			(layer "F.SilkS")
			(hide yes)
			(effects
				(font
					(size 1.27 1.27)
				)
			)
		)
		(property "Value" ""
			(at 0 0 90)
			(layer "F.Fab")
			(effects
				(font
					(size 1.27 1.27)
				)
			)
		)
		(duplicate_pad_numbers_are_jumpers no)
		(fp_line
			(start 0.7874 -0.4064)
			(end 0.7874 0.4064)
			(stroke
				(width 0.1524)
				(type default)
			)
			(layer "F.SilkS")
		)
		(fp_line
			(start -0.7874 -0.4064)
			(end 0.7874 -0.4064)
			(stroke
				(width 0.1524)
				(type default)
			)
			(layer "F.SilkS")
		)
		(fp_line
			(start 0.7874 0.4064)
			(end -0.7874 0.4064)
			(stroke
				(width 0.1524)
				(type default)
			)
			(layer "F.SilkS")
		)
		(fp_line
			(start -0.7874 0.4064)
			(end -0.7874 -0.4064)
			(stroke
				(width 0.1524)
				(type default)
			)
			(layer "F.SilkS")
		)
		(fp_line
			(start -0.12065 -0.305054)
			(end -0.12065 -0.2794)
			(stroke
				(width 0.1)
				(type default)
			)
			(layer "F.Fab")
		)
		(fp_line
			(start -0.67945 -0.305054)
			(end -0.12065 -0.305054)
			(stroke
				(width 0.1)
				(type default)
			)
			(layer "F.Fab")
		)
		(fp_line
			(start 0.67945 -0.3048)
			(end 0.67945 0.3048)
			(stroke
				(width 0.1)
				(type default)
			)
			(layer "F.Fab")
		)
		(fp_line
			(start 0.12065 -0.3048)
			(end 0.67945 -0.3048)
			(stroke
				(width 0.1)
				(type default)
			)
			(layer "F.Fab")
		)
		(fp_line
			(start 0.12065 -0.2794)
			(end 0.12065 -0.3048)
			(stroke
				(width 0.1)
				(type default)
			)
			(layer "F.Fab")
		)
		(fp_line
			(start -0.12065 -0.2794)
			(end 0.12065 -0.2794)
			(stroke
				(width 0.1)
				(type default)
			)
			(layer "F.Fab")
		)
		(fp_line
			(start 0.120396 0.2794)
			(end -0.12065 0.2794)
			(stroke
				(width 0.1)
				(type default)
			)
			(layer "F.Fab")
		)
		(fp_line
			(start -0.12065 0.2794)
			(end -0.12065 0.3048)
			(stroke
				(width 0.1)
				(type default)
			)
			(layer "F.Fab")
		)
		(fp_line
			(start 0.67945 0.3048)
			(end 0.120396 0.3048)
			(stroke
				(width 0.1)
				(type default)
			)
			(layer "F.Fab")
		)
		(fp_line
			(start 0.120396 0.3048)
			(end 0.120396 0.2794)
			(stroke
				(width 0.1)
				(type default)
			)
			(layer "F.Fab")
		)
		(fp_line
			(start -0.12065 0.3048)
			(end -0.67945 0.3048)
			(stroke
				(width 0.1)
				(type default)
			)
			(layer "F.Fab")
		)
		(fp_line
			(start -0.67945 0.3048)
			(end -0.67945 -0.305054)
			(stroke
				(width 0.1)
				(type default)
			)
			(layer "F.Fab")
		)
		(pad "1" smd circle
			(at -0.40005 0 90)
			(size 0 0)
			(layers "F.Cu" "F.Mask" "F.Paste")
			(net "PRSNT_CABLE_SWB_B2_ISO_N")
		)
		(pad "2" smd circle
			(at 0.40005 0 90)
			(size 0 0)
			(layers "F.Cu" "F.Mask" "F.Paste")
			(net "PRSNT_CABLE_SWB_B2_ISO_R_N")
		)
	)
)
